(kicad_pcb
	(version 20260206)
	(generator "pcbnew")
	(generator_version "10.0")
	(general
		(thickness 1.6)
		(legacy_teardrops no)
	)
	(paper "A4")
	(title_block
		(title "timecard-production-celestica-r4006 — R4006-B0001-02_R01.brd")
		(comment 1 "Time Appliance Project (Time Card) / footprint 197 of 1113 (U24), pads 338-453 of 484")
	)
	(layers
		(0 "F.Cu" signal "TOP")
		(4 "In1.Cu" signal "L02_GND1")
		(6 "In2.Cu" signal "L03_SIG1")
		(8 "In3.Cu" signal "L04_GND2")
		(10 "In4.Cu" signal "L05_VCC1")
		(12 "In5.Cu" signal "L06_VCC2")
		(14 "In6.Cu" signal "L07_GND3")
		(16 "In7.Cu" signal "L08_SIG2")
		(18 "In8.Cu" signal "L09_GND4")
		(2 "B.Cu" signal "BOTTOM")
		(9 "F.Adhes" user "F.Adhesive")
		(11 "B.Adhes" user "B.Adhesive")
		(13 "F.Paste" user "Package Geometry/Pastemask Top")
		(15 "B.Paste" user "Package Geometry/Pastemask Bottom")
		(5 "F.SilkS" user "Ref Des/Silkscreen Top")
		(7 "B.SilkS" user "Ref Des/Silkscreen Bottom")
		(1 "F.Mask" user "Board Geometry/Soldermask Top")
		(3 "B.Mask" user "Board Geometry/Soldermask Bottom")
		(17 "Dwgs.User" user "User.Drawings")
		(19 "Cmts.User" user "User.Comments")
		(21 "Eco1.User" user "User.Eco1")
		(23 "Eco2.User" user "User.Eco2")
		(25 "Edge.Cuts" user "Board Geometry/Outline")
		(27 "Margin" user)
		(31 "F.CrtYd" user "Package Geometry/Place Bound Top")
		(29 "B.CrtYd" user "Package Geometry/Place Bound Bottom")
		(35 "F.Fab" user "Ref Des/Assembly Top")
		(33 "B.Fab" user "Ref Des/Assembly Bottom")
	)
	(footprint ""
		(layer "F.Cu")
		(at 109.347 -44.323 90)
		(property "Reference" "U24"
			(at 12.27963 3.683 0)
			(unlocked yes)
			(layer "F.SilkS")
			(effects
				(font
					(size 0.7874 0.5842)
					(thickness 0.1524)
				)
			)
		)
		(property "Value" ""
			(at 0 0 90)
			(layer "F.Fab")
			(effects
				(font
					(size 1.27 1.27)
				)
			)
		)
		(property "User Part Number" "PARTNUM*"
			(at 0 14.056868 90)
			(unlocked yes)
			(layer "Cmts.User")
			(hide yes)
			(effects
				(font
					(size 0.7874 0.5842)
					(thickness 0.1524)
				)
			)
		)
		(property "Device Type" "XC7A200T_2FBG484C_FBG484-G240-A"
			(at 0 12.863068 90)
			(unlocked yes)
			(layer "F.Fab")
			(hide yes)
			(effects
				(font
					(size 0.7874 0.5842)
					(thickness 0.1524)
				)
			)
		)
		(duplicate_pad_numbers_are_jumpers no)
		(pad "P8" smd circle
			(at -3.499866 2.500122 90)
			(size 0.50038 0.50038)
			(layers "F.Cu" "F.Mask" "F.Paste")
			(net "XP1R0V_FPGA_VCCINT")
		)
		(pad "P9" smd circle
			(at -2.499868 2.500122 90)
			(size 0.50038 0.50038)
			(layers "F.Cu" "F.Mask" "F.Paste")
			(net "SG")
		)
		(pad "P10" smd circle
			(at -1.49987 2.500122 90)
			(size 0.50038 0.50038)
			(layers "F.Cu" "F.Mask" "F.Paste")
			(net "XP1R0V_FPGA_VCCINT")
		)
		(pad "P11" smd circle
			(at -0.499872 2.500122 90)
			(size 0.50038 0.50038)
			(layers "F.Cu" "F.Mask" "F.Paste")
			(net "SG")
		)
		(pad "P12" smd circle
			(at 0.500126 2.500122 90)
			(size 0.50038 0.50038)
			(layers "F.Cu" "F.Mask" "F.Paste")
			(net "XP1R8V_FPGA_VCCAUX")
		)
		(pad "P13" smd circle
			(at 1.500124 2.500122 90)
			(size 0.50038 0.50038)
			(layers "F.Cu" "F.Mask" "F.Paste")
			(net "SG")
		)
		(pad "P14" smd circle
			(at 2.500122 2.500122 90)
			(size 0.50038 0.50038)
			(layers "F.Cu" "F.Mask" "F.Paste")
			(net "MAC_USB_DP")
		)
		(pad "P15" smd circle
			(at 3.50012 2.500122 90)
			(size 0.50038 0.50038)
			(layers "F.Cu" "F.Mask" "F.Paste")
			(net "UART_FT4232_RX_FPGA_TX")
		)
		(pad "P16" smd circle
			(at 4.500118 2.500122 90)
			(size 0.50038 0.50038)
			(layers "F.Cu" "F.Mask" "F.Paste")
			(net "UART_FT4232_TX_FPGA_RX")
		)
		(pad "P17" smd circle
			(at 5.500116 2.500122 90)
			(size 0.50038 0.50038)
			(layers "F.Cu" "F.Mask" "F.Paste")
			(net "Net_63")
		)
		(pad "P18" smd circle
			(at 6.500114 2.500122 90)
			(size 0.50038 0.50038)
			(layers "F.Cu" "F.Mask" "F.Paste")
			(net "XP3R3V_FPGA")
		)
		(pad "P19" smd circle
			(at 7.500112 2.500122 90)
			(size 0.50038 0.50038)
			(layers "F.Cu" "F.Mask" "F.Paste")
			(net "Net_144")
		)
		(pad "P20" smd circle
			(at 8.50011 2.500122 90)
			(size 0.50038 0.50038)
			(layers "F.Cu" "F.Mask" "F.Paste")
			(net "UART_GPS_RX_FPGA_TX")
		)
		(pad "P21" smd circle
			(at 9.500108 2.500122 90)
			(size 0.50038 0.50038)
			(layers "F.Cu" "F.Mask" "F.Paste")
			(net "FPGA_D02")
		)
		(pad "P22" smd circle
			(at 10.500106 2.500122 90)
			(size 0.50038 0.50038)
			(layers "F.Cu" "F.Mask" "F.Paste")
			(net "FPGA_D00_MOSI")
		)
		(pad "R1" smd circle
			(at -10.500106 3.50012 90)
			(size 0.50038 0.50038)
			(layers "F.Cu" "F.Mask" "F.Paste")
			(net "IO_L20P_35")
		)
		(pad "R2" smd circle
			(at -9.500108 3.50012 90)
			(size 0.50038 0.50038)
			(layers "F.Cu" "F.Mask" "F.Paste")
			(net "Net_132")
		)
		(pad "R3" smd circle
			(at -8.50011 3.50012 90)
			(size 0.50038 0.50038)
			(layers "F.Cu" "F.Mask" "F.Paste")
			(net "Net_134")
		)
		(pad "R4" smd circle
			(at -7.499858 3.50012 90)
			(size 0.50038 0.50038)
			(layers "F.Cu" "F.Mask" "F.Paste")
			(net "MHZ200CLKP_CLKIN")
		)
		(pad "R5" smd circle
			(at -6.49986 3.50012 90)
			(size 0.50038 0.50038)
			(layers "F.Cu" "F.Mask" "F.Paste")
			(net "XP2R5V_FPGA")
		)
		(pad "R6" smd circle
			(at -5.499862 3.50012 90)
			(size 0.50038 0.50038)
			(layers "F.Cu" "F.Mask" "F.Paste")
			(net "Net_117")
		)
		(pad "R7" smd circle
			(at -4.499864 3.50012 90)
			(size 0.50038 0.50038)
			(layers "F.Cu" "F.Mask" "F.Paste")
			(net "XP1R0V_FPGA_VCCINT")
		)
		(pad "R8" smd circle
			(at -3.499866 3.50012 90)
			(size 0.50038 0.50038)
			(layers "F.Cu" "F.Mask" "F.Paste")
			(net "SG")
		)
		(pad "R9" smd circle
			(at -2.499868 3.50012 90)
			(size 0.50038 0.50038)
			(layers "F.Cu" "F.Mask" "F.Paste")
			(net "XP1R0V_FPGA_VCCINT")
		)
		(pad "R10" smd circle
			(at -1.49987 3.50012 90)
			(size 0.50038 0.50038)
			(layers "F.Cu" "F.Mask" "F.Paste")
			(net "SG")
		)
		(pad "R11" smd circle
			(at -0.499872 3.50012 90)
			(size 0.50038 0.50038)
			(layers "F.Cu" "F.Mask" "F.Paste")
			(net "XP1R8V_FPGA_VCCAUX")
		)
		(pad "R12" smd circle
			(at 0.500126 3.50012 90)
			(size 0.50038 0.50038)
			(layers "F.Cu" "F.Mask" "F.Paste")
			(net "SG")
		)
		(pad "R13" smd circle
			(at 1.500124 3.50012 90)
			(size 0.50038 0.50038)
			(layers "F.Cu" "F.Mask" "F.Paste")
			(net "FPGA_TDI")
		)
		(pad "R14" smd circle
			(at 2.500122 3.50012 90)
			(size 0.50038 0.50038)
			(layers "F.Cu" "F.Mask" "F.Paste")
			(net "MAC_USB_DM")
		)
		(pad "R15" smd circle
			(at 3.50012 3.50012 90)
			(size 0.50038 0.50038)
			(layers "F.Cu" "F.Mask" "F.Paste")
			(net "XP3R3V_FPGA")
		)
		(pad "R16" smd circle
			(at 4.500118 3.50012 90)
			(size 0.50038 0.50038)
			(layers "F.Cu" "F.Mask" "F.Paste")
			(net "Net_64")
		)
		(pad "R17" smd circle
			(at 5.500116 3.50012 90)
			(size 0.50038 0.50038)
			(layers "F.Cu" "F.Mask" "F.Paste")
			(net "Net_67")
		)
		(pad "R18" smd circle
			(at 6.500114 3.50012 90)
			(size 0.50038 0.50038)
			(layers "F.Cu" "F.Mask" "F.Paste")
			(net "Net_62")
		)
		(pad "R19" smd circle
			(at 7.500112 3.50012 90)
			(size 0.50038 0.50038)
			(layers "F.Cu" "F.Mask" "F.Paste")
			(net "Net_141")
		)
		(pad "R20" smd circle
			(at 8.50011 3.50012 90)
			(size 0.50038 0.50038)
			(layers "F.Cu" "F.Mask" "F.Paste")
			(net "SG")
		)
		(pad "R21" smd circle
			(at 9.500108 3.50012 90)
			(size 0.50038 0.50038)
			(layers "F.Cu" "F.Mask" "F.Paste")
			(net "FPGA_D03")
		)
		(pad "R22" smd circle
			(at 10.500106 3.50012 90)
			(size 0.50038 0.50038)
			(layers "F.Cu" "F.Mask" "F.Paste")
			(net "FPGA_D01")
		)
		(pad "T1" smd circle
			(at -10.500106 4.500118 90)
			(size 0.50038 0.50038)
			(layers "F.Cu" "F.Mask" "F.Paste")
			(net "Net_125")
		)
		(pad "T2" smd circle
			(at -9.500108 4.500118 90)
			(size 0.50038 0.50038)
			(layers "F.Cu" "F.Mask" "F.Paste")
			(net "XP2R5V_FPGA")
		)
		(pad "T3" smd circle
			(at -8.50011 4.500118 90)
			(size 0.50038 0.50038)
			(layers "F.Cu" "F.Mask" "F.Paste")
			(net "Net_29")
		)
		(pad "T4" smd circle
			(at -7.499858 4.500118 90)
			(size 0.50038 0.50038)
			(layers "F.Cu" "F.Mask" "F.Paste")
			(net "MHZ200CLKN_CLKIN")
		)
		(pad "T5" smd circle
			(at -6.49986 4.500118 90)
			(size 0.50038 0.50038)
			(layers "F.Cu" "F.Mask" "F.Paste")
			(net "Net_106")
		)
		(pad "T6" smd circle
			(at -5.499862 4.500118 90)
			(size 0.50038 0.50038)
			(layers "F.Cu" "F.Mask" "F.Paste")
			(net "Net_14")
		)
		(pad "T7" smd circle
			(at -4.499864 4.500118 90)
			(size 0.50038 0.50038)
			(layers "F.Cu" "F.Mask" "F.Paste")
			(net "SG")
		)
		(pad "T8" smd circle
			(at -3.499866 4.500118 90)
			(size 0.50038 0.50038)
			(layers "F.Cu" "F.Mask" "F.Paste")
			(net "XP1R0V_FPGA_VCCINT")
		)
		(pad "T9" smd circle
			(at -2.499868 4.500118 90)
			(size 0.50038 0.50038)
			(layers "F.Cu" "F.Mask" "F.Paste")
			(net "SG")
		)
		(pad "T10" smd circle
			(at -1.49987 4.500118 90)
			(size 0.50038 0.50038)
			(layers "F.Cu" "F.Mask" "F.Paste")
			(net "XP1R0V_FPGA_VCCINT")
		)
		(pad "T11" smd circle
			(at -0.499872 4.500118 90)
			(size 0.50038 0.50038)
			(layers "F.Cu" "F.Mask" "F.Paste")
			(net "SG")
		)
		(pad "T12" smd circle
			(at 0.500126 4.500118 90)
			(size 0.50038 0.50038)
			(layers "F.Cu" "F.Mask" "F.Paste")
			(net "XP3R3V_FPGA")
		)
		(pad "T13" smd circle
			(at 1.500124 4.500118 90)
			(size 0.50038 0.50038)
			(layers "F.Cu" "F.Mask" "F.Paste")
			(net "FPGA_TMS")
		)
		(pad "T14" smd circle
			(at 2.500122 4.500118 90)
			(size 0.50038 0.50038)
			(layers "F.Cu" "F.Mask" "F.Paste")
			(net "Net_41")
		)
		(pad "T15" smd circle
			(at 3.50012 4.500118 90)
			(size 0.50038 0.50038)
			(layers "F.Cu" "F.Mask" "F.Paste")
			(net "Net_38")
		)
		(pad "T16" smd circle
			(at 4.500118 4.500118 90)
			(size 0.50038 0.50038)
			(layers "F.Cu" "F.Mask" "F.Paste")
			(net "FPGA_PCA9546_I2C_SDA")
		)
		(pad "T17" smd circle
			(at 5.500116 4.500118 90)
			(size 0.50038 0.50038)
			(layers "F.Cu" "F.Mask" "F.Paste")
			(net "SG")
		)
		(pad "T18" smd circle
			(at 6.500114 4.500118 90)
			(size 0.50038 0.50038)
			(layers "F.Cu" "F.Mask" "F.Paste")
			(net "Net_61")
		)
		(pad "T19" smd circle
			(at 7.500112 4.500118 90)
			(size 0.50038 0.50038)
			(layers "F.Cu" "F.Mask" "F.Paste")
			(net "FPGA_FCS_B")
		)
		(pad "T20" smd circle
			(at 8.50011 4.500118 90)
			(size 0.50038 0.50038)
			(layers "F.Cu" "F.Mask" "F.Paste")
			(net "Net_77")
		)
		(pad "T21" smd circle
			(at 9.500108 4.500118 90)
			(size 0.50038 0.50038)
			(layers "F.Cu" "F.Mask" "F.Paste")
			(net "Net_74")
		)
		(pad "T22" smd circle
			(at 10.500106 4.500118 90)
			(size 0.50038 0.50038)
			(layers "F.Cu" "F.Mask" "F.Paste")
			(net "XP3R3V_FPGA")
		)
		(pad "U1" smd circle
			(at -10.500106 5.500116 90)
			(size 0.50038 0.50038)
			(layers "F.Cu" "F.Mask" "F.Paste")
			(net "Net_123")
		)
		(pad "U2" smd circle
			(at -9.500108 5.500116 90)
			(size 0.50038 0.50038)
			(layers "F.Cu" "F.Mask" "F.Paste")
			(net "Net_130")
		)
		(pad "U3" smd circle
			(at -8.50011 5.500116 90)
			(size 0.50038 0.50038)
			(layers "F.Cu" "F.Mask" "F.Paste")
			(net "Net_148")
		)
		(pad "U4" smd circle
			(at -7.499858 5.500116 90)
			(size 0.50038 0.50038)
			(layers "F.Cu" "F.Mask" "F.Paste")
			(net "SG")
		)
		(pad "U5" smd circle
			(at -6.49986 5.500116 90)
			(size 0.50038 0.50038)
			(layers "F.Cu" "F.Mask" "F.Paste")
			(net "Net_104")
		)
		(pad "U6" smd circle
			(at -5.499862 5.500116 90)
			(size 0.50038 0.50038)
			(layers "F.Cu" "F.Mask" "F.Paste")
			(net "Net_114")
		)
		(pad "U7" smd circle
			(at -4.499864 5.500116 90)
			(size 0.50038 0.50038)
			(layers "F.Cu" "F.Mask" "F.Paste")
			(net "Net_88")
		)
		(pad "U8" smd circle
			(at -3.499866 5.500116 90)
			(size 0.50038 0.50038)
			(layers "F.Cu" "F.Mask" "F.Paste")
			(net "CFGBVS")
		)
		(pad "U9" smd circle
			(at -2.499868 5.500116 90)
			(size 0.50038 0.50038)
			(layers "F.Cu" "F.Mask" "F.Paste")
			(net "FPGA_M2")
		)
		(pad "U10" smd circle
			(at -1.49987 5.500116 90)
			(size 0.50038 0.50038)
			(layers "F.Cu" "F.Mask" "F.Paste")
			(net "FPGA_M1")
		)
		(pad "U11" smd circle
			(at -0.499872 5.500116 90)
			(size 0.50038 0.50038)
			(layers "F.Cu" "F.Mask" "F.Paste")
			(net "FPGA_M0")
		)
		(pad "U12" smd circle
			(at 0.500126 5.500116 90)
			(size 0.50038 0.50038)
			(layers "F.Cu" "F.Mask" "F.Paste")
			(net "FPGA_CFG_INIT_N")
		)
		(pad "U13" smd circle
			(at 1.500124 5.500116 90)
			(size 0.50038 0.50038)
			(layers "F.Cu" "F.Mask" "F.Paste")
			(net "R_FPGA_TDO")
		)
		(pad "U14" smd circle
			(at 2.500122 5.500116 90)
			(size 0.50038 0.50038)
			(layers "F.Cu" "F.Mask" "F.Paste")
			(net "SG")
		)
		(pad "U15" smd circle
			(at 3.50012 5.500116 90)
			(size 0.50038 0.50038)
			(layers "F.Cu" "F.Mask" "F.Paste")
			(net "Net_169")
		)
		(pad "U16" smd circle
			(at 4.500118 5.500116 90)
			(size 0.50038 0.50038)
			(layers "F.Cu" "F.Mask" "F.Paste")
			(net "FPGA_OUT_PCA9546_RST_N")
		)
		(pad "U17" smd circle
			(at 5.500116 5.500116 90)
			(size 0.50038 0.50038)
			(layers "F.Cu" "F.Mask" "F.Paste")
			(net "Net_53")
		)
		(pad "U18" smd circle
			(at 6.500114 5.500116 90)
			(size 0.50038 0.50038)
			(layers "F.Cu" "F.Mask" "F.Paste")
			(net "Net_49")
		)
		(pad "U19" smd circle
			(at 7.500112 5.500116 90)
			(size 0.50038 0.50038)
			(layers "F.Cu" "F.Mask" "F.Paste")
			(net "XP3R3V_FPGA")
		)
		(pad "U20" smd circle
			(at 8.50011 5.500116 90)
			(size 0.50038 0.50038)
			(layers "F.Cu" "F.Mask" "F.Paste")
			(net "Net_165")
		)
		(pad "U21" smd circle
			(at 9.500108 5.500116 90)
			(size 0.50038 0.50038)
			(layers "F.Cu" "F.Mask" "F.Paste")
			(net "Net_72")
		)
		(pad "U22" smd circle
			(at 10.500106 5.500116 90)
			(size 0.50038 0.50038)
			(layers "F.Cu" "F.Mask" "F.Paste")
			(net "PUDC")
		)
		(pad "V1" smd circle
			(at -10.500106 6.500114 90)
			(size 0.50038 0.50038)
			(layers "F.Cu" "F.Mask" "F.Paste")
			(net "SG")
		)
		(pad "V2" smd circle
			(at -9.500108 6.500114 90)
			(size 0.50038 0.50038)
			(layers "F.Cu" "F.Mask" "F.Paste")
			(net "Net_128")
		)
		(pad "V3" smd circle
			(at -8.50011 6.500114 90)
			(size 0.50038 0.50038)
			(layers "F.Cu" "F.Mask" "F.Paste")
			(net "Net_146")
		)
		(pad "V4" smd circle
			(at -7.499858 6.500114 90)
			(size 0.50038 0.50038)
			(layers "F.Cu" "F.Mask" "F.Paste")
			(net "Net_100")
		)
		(pad "V5" smd circle
			(at -6.49986 6.500114 90)
			(size 0.50038 0.50038)
			(layers "F.Cu" "F.Mask" "F.Paste")
			(net "Net_112")
		)
		(pad "V6" smd circle
			(at -5.499862 6.500114 90)
			(size 0.50038 0.50038)
			(layers "F.Cu" "F.Mask" "F.Paste")
			(net "XP2R5V_FPGA")
		)
		(pad "V7" smd circle
			(at -4.499864 6.500114 90)
			(size 0.50038 0.50038)
			(layers "F.Cu" "F.Mask" "F.Paste")
			(net "Net_59")
		)
		(pad "V8" smd circle
			(at -3.499866 6.500114 90)
			(size 0.50038 0.50038)
			(layers "F.Cu" "F.Mask" "F.Paste")
			(net "IO_L21N_34")
		)
		(pad "V9" smd circle
			(at -2.499868 6.500114 90)
			(size 0.50038 0.50038)
			(layers "F.Cu" "F.Mask" "F.Paste")
			(net "IO_L21P_34")
		)
		(pad "V10" smd circle
			(at -1.49987 6.500114 90)
			(size 0.50038 0.50038)
			(layers "F.Cu" "F.Mask" "F.Paste")
			(net "ANT1_OUT")
		)
		(pad "V11" smd circle
			(at -0.499872 6.500114 90)
			(size 0.50038 0.50038)
			(layers "F.Cu" "F.Mask" "F.Paste")
			(net "SG")
		)
		(pad "V12" smd circle
			(at 0.500126 6.500114 90)
			(size 0.50038 0.50038)
			(layers "F.Cu" "F.Mask" "F.Paste")
			(net "FPGA_TCK")
		)
		(pad "V13" smd circle
			(at 1.500124 6.500114 90)
			(size 0.50038 0.50038)
			(layers "F.Cu" "F.Mask" "F.Paste")
			(net "FPGA_IN_MAC_10MHZ_OUT")
		)
		(pad "V14" smd circle
			(at 2.500122 6.500114 90)
			(size 0.50038 0.50038)
			(layers "F.Cu" "F.Mask" "F.Paste")
			(net "Net_166")
		)
		(pad "V15" smd circle
			(at 3.50012 6.500114 90)
			(size 0.50038 0.50038)
			(layers "F.Cu" "F.Mask" "F.Paste")
			(net "FPGA_OUT_MACUSBPOWER_EN")
		)
		(pad "V16" smd circle
			(at 4.500118 6.500114 90)
			(size 0.50038 0.50038)
			(layers "F.Cu" "F.Mask" "F.Paste")
			(net "XP3R3V_FPGA")
		)
		(pad "V17" smd circle
			(at 5.500116 6.500114 90)
			(size 0.50038 0.50038)
			(layers "F.Cu" "F.Mask" "F.Paste")
			(net "Net_47")
		)
		(pad "V18" smd circle
			(at 6.500114 6.500114 90)
			(size 0.50038 0.50038)
			(layers "F.Cu" "F.Mask" "F.Paste")
			(net "Net_170")
		)
		(pad "V19" smd circle
			(at 7.500112 6.500114 90)
			(size 0.50038 0.50038)
			(layers "F.Cu" "F.Mask" "F.Paste")
			(net "Net_168")
		)
		(pad "V20" smd circle
			(at 8.50011 6.500114 90)
			(size 0.50038 0.50038)
			(layers "F.Cu" "F.Mask" "F.Paste")
			(net "Net_164")
		)
		(pad "V21" smd circle
			(at 9.500108 6.500114 90)
			(size 0.50038 0.50038)
			(layers "F.Cu" "F.Mask" "F.Paste")
			(net "SG")
		)
		(pad "V22" smd circle
			(at 10.500106 6.500114 90)
			(size 0.50038 0.50038)
			(layers "F.Cu" "F.Mask" "F.Paste")
			(net "Net_70")
		)
		(pad "W1" smd circle
			(at -10.500106 7.500112 90)
			(size 0.50038 0.50038)
			(layers "F.Cu" "F.Mask" "F.Paste")
			(net "FPGA_IN_MAC_PPS_OUTP")
		)
		(pad "W2" smd circle
			(at -9.500108 7.500112 90)
			(size 0.50038 0.50038)
			(layers "F.Cu" "F.Mask" "F.Paste")
			(net "Net_138")
		)
		(pad "W3" smd circle
			(at -8.50011 7.500112 90)
			(size 0.50038 0.50038)
			(layers "F.Cu" "F.Mask" "F.Paste")
			(net "XP2R5V_FPGA")
		)
		(pad "W4" smd circle
			(at -7.499858 7.500112 90)
			(size 0.50038 0.50038)
			(layers "F.Cu" "F.Mask" "F.Paste")
			(net "Net_98")
		)
		(pad "W5" smd circle
			(at -6.49986 7.500112 90)
			(size 0.50038 0.50038)
			(layers "F.Cu" "F.Mask" "F.Paste")
			(net "Net_108")
		)
		(pad "W6" smd circle
			(at -5.499862 7.500112 90)
			(size 0.50038 0.50038)
			(layers "F.Cu" "F.Mask" "F.Paste")
			(net "Net_110")
		)
		(pad "W7" smd circle
			(at -4.499864 7.500112 90)
			(size 0.50038 0.50038)
			(layers "F.Cu" "F.Mask" "F.Paste")
			(net "Net_57")
		)
		(pad "W8" smd circle
			(at -3.499866 7.500112 90)
			(size 0.50038 0.50038)
			(layers "F.Cu" "F.Mask" "F.Paste")
			(net "SG")
		)
		(pad "W9" smd circle
			(at -2.499868 7.500112 90)
			(size 0.50038 0.50038)
			(layers "F.Cu" "F.Mask" "F.Paste")
			(net "IO_L24P_34")
		)
		(pad "W10" smd circle
			(at -1.49987 7.500112 90)
			(size 0.50038 0.50038)
			(layers "F.Cu" "F.Mask" "F.Paste")
			(net "ANT2_OUT")
		)
		(pad "W11" smd circle
			(at -0.499872 7.500112 90)
			(size 0.50038 0.50038)
			(layers "F.Cu" "F.Mask" "F.Paste")
			(net "ANT3_OUT")
		)
		(pad "W12" smd circle
			(at 0.500126 7.500112 90)
			(size 0.50038 0.50038)
			(layers "F.Cu" "F.Mask" "F.Paste")
			(net "ANT4_OUT")
		)
		(pad "W13" smd circle
			(at 1.500124 7.500112 90)
			(size 0.50038 0.50038)
			(layers "F.Cu" "F.Mask" "F.Paste")
			(net "XP3R3V_FPGA")
		)
	)
)
